(kicad_pcb
	(version 20260206)
	(generator "pcbnew")
	(generator_version "10.0")
	(general
		(thickness 1.6)
		(legacy_teardrops no)
	)
	(paper "A4")
	(title_block
		(title "01162023_DA0F0TEBIF0_F0T_Expander_BD_F_brd_V02_OCP.brd")
		(comment 1 "Grand Teton / footprints 6064-6070 of 9728")
	)
	(layers
		(0 "F.Cu" signal "TOP")
		(4 "In1.Cu" signal "GND")
		(6 "In2.Cu" signal "VCC")
		(8 "In3.Cu" signal "VCC1")
		(10 "In4.Cu" signal "GND1")
		(12 "In5.Cu" signal "IN1")
		(14 "In6.Cu" signal "GND2")
		(16 "In7.Cu" signal "IN2")
		(18 "In8.Cu" signal "GND3")
		(20 "In9.Cu" signal "IN3")
		(22 "In10.Cu" signal "GND4")
		(24 "In11.Cu" signal "IN4")
		(26 "In12.Cu" signal "GND5")
		(28 "In13.Cu" signal "IN5")
		(30 "In14.Cu" signal "GND6")
		(32 "In15.Cu" signal "IN6")
		(34 "In16.Cu" signal "GND7")
		(2 "B.Cu" signal "BOTTOM")
		(9 "F.Adhes" user "F.Adhesive")
		(11 "B.Adhes" user "B.Adhesive")
		(13 "F.Paste" user "Package Geometry/Pastemask Top")
		(15 "B.Paste" user "Package Geometry/Pastemask Bottom")
		(5 "F.SilkS" user "Ref Des/Silkscreen Top")
		(7 "B.SilkS" user "Ref Des/Silkscreen Bottom")
		(1 "F.Mask" user "Board Geometry/Soldermask Top")
		(3 "B.Mask" user "Board Geometry/Soldermask Bottom")
		(17 "Dwgs.User" user "User.Drawings")
		(19 "Cmts.User" user "User.Comments")
		(21 "Eco1.User" user "User.Eco1")
		(23 "Eco2.User" user "User.Eco2")
		(25 "Edge.Cuts" user "Board Geometry/Outline")
		(27 "Margin" user)
		(31 "F.CrtYd" user "Package Geometry/Place Bound Top")
		(29 "B.CrtYd" user "Package Geometry/Place Bound Bottom")
		(35 "F.Fab" user "Ref Des/Assembly Top")
		(33 "B.Fab" user "Ref Des/Assembly Bottom")
	)
	(footprint ""
		(layer "F.Cu")
		(at 103.80472 -10.545572 90)
		(property "Reference" "R1650"
			(at 0 0 90)
			(layer "F.SilkS")
			(hide yes)
			(effects
				(font
					(size 1.27 1.27)
				)
			)
		)
		(property "Value" ""
			(at 0 0 90)
			(layer "F.Fab")
			(effects
				(font
					(size 1.27 1.27)
				)
			)
		)
		(duplicate_pad_numbers_are_jumpers no)
		(fp_line
			(start 0.7874 -0.4064)
			(end 0.7874 0.4064)
			(stroke
				(width 0.1524)
				(type default)
			)
			(layer "F.SilkS")
		)
		(fp_line
			(start -0.7874 -0.4064)
			(end 0.7874 -0.4064)
			(stroke
				(width 0.1524)
				(type default)
			)
			(layer "F.SilkS")
		)
		(fp_line
			(start 0.7874 0.4064)
			(end -0.7874 0.4064)
			(stroke
				(width 0.1524)
				(type default)
			)
			(layer "F.SilkS")
		)
		(fp_line
			(start -0.7874 0.4064)
			(end -0.7874 -0.4064)
			(stroke
				(width 0.1524)
				(type default)
			)
			(layer "F.SilkS")
		)
		(fp_line
			(start -0.12065 -0.305054)
			(end -0.12065 -0.2794)
			(stroke
				(width 0.1)
				(type default)
			)
			(layer "F.Fab")
		)
		(fp_line
			(start -0.67945 -0.305054)
			(end -0.12065 -0.305054)
			(stroke
				(width 0.1)
				(type default)
			)
			(layer "F.Fab")
		)
		(fp_line
			(start 0.67945 -0.3048)
			(end 0.67945 0.3048)
			(stroke
				(width 0.1)
				(type default)
			)
			(layer "F.Fab")
		)
		(fp_line
			(start 0.12065 -0.3048)
			(end 0.67945 -0.3048)
			(stroke
				(width 0.1)
				(type default)
			)
			(layer "F.Fab")
		)
		(fp_line
			(start 0.12065 -0.2794)
			(end 0.12065 -0.3048)
			(stroke
				(width 0.1)
				(type default)
			)
			(layer "F.Fab")
		)
		(fp_line
			(start -0.12065 -0.2794)
			(end 0.12065 -0.2794)
			(stroke
				(width 0.1)
				(type default)
			)
			(layer "F.Fab")
		)
		(fp_line
			(start 0.120396 0.2794)
			(end -0.12065 0.2794)
			(stroke
				(width 0.1)
				(type default)
			)
			(layer "F.Fab")
		)
		(fp_line
			(start -0.12065 0.2794)
			(end -0.12065 0.3048)
			(stroke
				(width 0.1)
				(type default)
			)
			(layer "F.Fab")
		)
		(fp_line
			(start 0.67945 0.3048)
			(end 0.120396 0.3048)
			(stroke
				(width 0.1)
				(type default)
			)
			(layer "F.Fab")
		)
		(fp_line
			(start 0.120396 0.3048)
			(end 0.120396 0.2794)
			(stroke
				(width 0.1)
				(type default)
			)
			(layer "F.Fab")
		)
		(fp_line
			(start -0.12065 0.3048)
			(end -0.67945 0.3048)
			(stroke
				(width 0.1)
				(type default)
			)
			(layer "F.Fab")
		)
		(fp_line
			(start -0.67945 0.3048)
			(end -0.67945 -0.305054)
			(stroke
				(width 0.1)
				(type default)
			)
			(layer "F.Fab")
		)
		(pad "1" smd circle
			(at -0.40005 0 90)
			(size 0 0)
			(layers "F.Cu" "F.Mask" "F.Paste")
			(net "P3V3_SSD3")
		)
		(pad "2" smd circle
			(at 0.40005 0 90)
			(size 0 0)
			(layers "F.Cu" "F.Mask" "F.Paste")
			(net "SMB_ISO_SSD3_SDA")
		)
	)
	(footprint ""
		(layer "F.Cu")
		(at 149.387814 -301.220632)
		(property "Reference" "C3198"
			(at 0 0 0)
			(layer "F.SilkS")
			(hide yes)
			(effects
				(font
					(size 1.27 1.27)
				)
			)
		)
		(property "Value" ""
			(at 0 0 0)
			(layer "F.Fab")
			(effects
				(font
					(size 1.27 1.27)
				)
			)
		)
		(duplicate_pad_numbers_are_jumpers no)
		(fp_line
			(start -1.2954 -0.5842)
			(end 1.2954 -0.5842)
			(stroke
				(width 0.1524)
				(type default)
			)
			(layer "F.SilkS")
		)
		(fp_line
			(start -1.2954 0.5842)
			(end -1.2954 -0.5842)
			(stroke
				(width 0.1524)
				(type default)
			)
			(layer "F.SilkS")
		)
		(fp_line
			(start 1.2954 -0.5842)
			(end 1.2954 0.5842)
			(stroke
				(width 0.1524)
				(type default)
			)
			(layer "F.SilkS")
		)
		(fp_line
			(start 1.2954 0.5842)
			(end -1.2954 0.5842)
			(stroke
				(width 0.1524)
				(type default)
			)
			(layer "F.SilkS")
		)
		(fp_line
			(start -1.1938 -0.4064)
			(end -0.8636 -0.4064)
			(stroke
				(width 0.1)
				(type default)
			)
			(layer "F.Fab")
		)
		(fp_line
			(start -1.1938 0.4064)
			(end -1.1938 -0.4064)
			(stroke
				(width 0.1)
				(type default)
			)
			(layer "F.Fab")
		)
		(fp_line
			(start -0.8636 -0.4572)
			(end 0.8636 -0.4572)
			(stroke
				(width 0.1)
				(type default)
			)
			(layer "F.Fab")
		)
		(fp_line
			(start -0.8636 -0.4064)
			(end -0.8636 -0.4572)
			(stroke
				(width 0.1)
				(type default)
			)
			(layer "F.Fab")
		)
		(fp_line
			(start -0.8636 0.4064)
			(end -1.1938 0.4064)
			(stroke
				(width 0.1)
				(type default)
			)
			(layer "F.Fab")
		)
		(fp_line
			(start -0.8636 0.4572)
			(end -0.8636 0.4064)
			(stroke
				(width 0.1)
				(type default)
			)
			(layer "F.Fab")
		)
		(fp_line
			(start 0.8636 -0.4572)
			(end 0.8636 -0.4064)
			(stroke
				(width 0.1)
				(type default)
			)
			(layer "F.Fab")
		)
		(fp_line
			(start 0.8636 -0.4064)
			(end 1.1938 -0.4064)
			(stroke
				(width 0.1)
				(type default)
			)
			(layer "F.Fab")
		)
		(fp_line
			(start 0.8636 0.4064)
			(end 0.8636 0.4572)
			(stroke
				(width 0.1)
				(type default)
			)
			(layer "F.Fab")
		)
		(fp_line
			(start 0.8636 0.4572)
			(end -0.8636 0.4572)
			(stroke
				(width 0.1)
				(type default)
			)
			(layer "F.Fab")
		)
		(fp_line
			(start 1.1938 -0.4064)
			(end 1.1938 0.4064)
			(stroke
				(width 0.1)
				(type default)
			)
			(layer "F.Fab")
		)
		(fp_line
			(start 1.1938 0.4064)
			(end 0.8636 0.4064)
			(stroke
				(width 0.1)
				(type default)
			)
			(layer "F.Fab")
		)
		(pad "1" smd rect
			(at -0.7366 0 270)
			(size 0.7112 0.8128)
			(layers "F.Cu" "F.Mask" "F.Paste")
			(net "PCEPLL1_VDDA18_PEX1")
		)
		(pad "2" smd rect
			(at 0.7366 0 270)
			(size 0.7112 0.8128)
			(layers "F.Cu" "F.Mask" "F.Paste")
			(net "GND")
		)
	)
	(footprint ""
		(layer "F.Cu")
		(at 39.280592 -136.729724)
		(property "Reference" "C34"
			(at 0 0 0)
			(layer "F.SilkS")
			(hide yes)
			(effects
				(font
					(size 1.27 1.27)
				)
			)
		)
		(property "Value" ""
			(at 0 0 0)
			(layer "F.Fab")
			(effects
				(font
					(size 1.27 1.27)
				)
			)
		)
		(duplicate_pad_numbers_are_jumpers no)
		(fp_line
			(start -0.299974 -0.150114)
			(end 0.299974 -0.150114)
			(stroke
				(width 0.1)
				(type default)
			)
			(layer "F.Fab")
		)
		(fp_line
			(start -0.299974 0.150114)
			(end -0.299974 -0.150114)
			(stroke
				(width 0.1)
				(type default)
			)
			(layer "F.Fab")
		)
		(fp_line
			(start 0.299974 -0.150114)
			(end 0.299974 0.150114)
			(stroke
				(width 0.1)
				(type default)
			)
			(layer "F.Fab")
		)
		(fp_line
			(start 0.299974 0.150114)
			(end -0.299974 0.150114)
			(stroke
				(width 0.1)
				(type default)
			)
			(layer "F.Fab")
		)
		(pad "1" smd rect
			(at -0.2667 0)
			(size 0.3048 0.381)
			(layers "F.Cu" "F.Mask" "F.Paste")
			(net "P5E_PEX0_STN1_TX_DP<31>")
		)
		(pad "2" smd rect
			(at 0.2667 0)
			(size 0.3048 0.381)
			(layers "F.Cu" "F.Mask" "F.Paste")
			(net "P5E_PEX0_STN1_TX_C_DP<31>")
		)
	)
	(footprint ""
		(layer "F.Cu")
		(at 329.996038 -47.20082 90)
		(property "Reference" "C331"
			(at 0 0 90)
			(layer "F.SilkS")
			(hide yes)
			(effects
				(font
					(size 1.27 1.27)
				)
			)
		)
		(property "Value" ""
			(at 0 0 90)
			(layer "F.Fab")
			(effects
				(font
					(size 1.27 1.27)
				)
			)
		)
		(duplicate_pad_numbers_are_jumpers no)
		(fp_line
			(start 0.7874 -0.4064)
			(end 0.7874 0.4064)
			(stroke
				(width 0.1524)
				(type default)
			)
			(layer "F.SilkS")
		)
		(fp_line
			(start -0.7874 -0.4064)
			(end 0.7874 -0.4064)
			(stroke
				(width 0.1524)
				(type default)
			)
			(layer "F.SilkS")
		)
		(fp_line
			(start 0.7874 0.4064)
			(end -0.7874 0.4064)
			(stroke
				(width 0.1524)
				(type default)
			)
			(layer "F.SilkS")
		)
		(fp_line
			(start -0.7874 0.4064)
			(end -0.7874 -0.4064)
			(stroke
				(width 0.1524)
				(type default)
			)
			(layer "F.SilkS")
		)
		(fp_line
			(start -0.12065 -0.305054)
			(end -0.12065 -0.2794)
			(stroke
				(width 0.1)
				(type default)
			)
			(layer "F.Fab")
		)
		(fp_line
			(start -0.67945 -0.305054)
			(end -0.12065 -0.305054)
			(stroke
				(width 0.1)
				(type default)
			)
			(layer "F.Fab")
		)
		(fp_line
			(start 0.67945 -0.3048)
			(end 0.67945 0.3048)
			(stroke
				(width 0.1)
				(type default)
			)
			(layer "F.Fab")
		)
		(fp_line
			(start 0.12065 -0.3048)
			(end 0.67945 -0.3048)
			(stroke
				(width 0.1)
				(type default)
			)
			(layer "F.Fab")
		)
		(fp_line
			(start 0.12065 -0.2794)
			(end 0.12065 -0.3048)
			(stroke
				(width 0.1)
				(type default)
			)
			(layer "F.Fab")
		)
		(fp_line
			(start -0.12065 -0.2794)
			(end 0.12065 -0.2794)
			(stroke
				(width 0.1)
				(type default)
			)
			(layer "F.Fab")
		)
		(fp_line
			(start 0.120396 0.2794)
			(end -0.12065 0.2794)
			(stroke
				(width 0.1)
				(type default)
			)
			(layer "F.Fab")
		)
		(fp_line
			(start -0.12065 0.2794)
			(end -0.12065 0.3048)
			(stroke
				(width 0.1)
				(type default)
			)
			(layer "F.Fab")
		)
		(fp_line
			(start 0.67945 0.3048)
			(end 0.120396 0.3048)
			(stroke
				(width 0.1)
				(type default)
			)
			(layer "F.Fab")
		)
		(fp_line
			(start 0.120396 0.3048)
			(end 0.120396 0.2794)
			(stroke
				(width 0.1)
				(type default)
			)
			(layer "F.Fab")
		)
		(fp_line
			(start -0.12065 0.3048)
			(end -0.67945 0.3048)
			(stroke
				(width 0.1)
				(type default)
			)
			(layer "F.Fab")
		)
		(fp_line
			(start -0.67945 0.3048)
			(end -0.67945 -0.305054)
			(stroke
				(width 0.1)
				(type default)
			)
			(layer "F.Fab")
		)
		(pad "1" smd circle
			(at -0.40005 0 90)
			(size 0 0)
			(layers "F.Cu" "F.Mask" "F.Paste")
			(net "P12V_SSD11_R")
		)
		(pad "2" smd circle
			(at 0.40005 0 90)
			(size 0 0)
			(layers "F.Cu" "F.Mask" "F.Paste")
			(net "GND")
		)
	)
	(footprint ""
		(layer "F.Cu")
		(at 202.210416 -63.652146 180)
		(property "Reference" "R5987"
			(at 0 0 180)
			(layer "F.SilkS")
			(hide yes)
			(effects
				(font
					(size 1.27 1.27)
				)
			)
		)
		(property "Value" ""
			(at 0 0 180)
			(layer "F.Fab")
			(effects
				(font
					(size 1.27 1.27)
				)
			)
		)
		(duplicate_pad_numbers_are_jumpers no)
		(fp_line
			(start 0.7874 0.4064)
			(end -0.7874 0.4064)
			(stroke
				(width 0.1524)
				(type default)
			)
			(layer "F.SilkS")
		)
		(fp_line
			(start 0.7874 -0.4064)
			(end 0.7874 0.4064)
			(stroke
				(width 0.1524)
				(type default)
			)
			(layer "F.SilkS")
		)
		(fp_line
			(start -0.7874 0.4064)
			(end -0.7874 -0.4064)
			(stroke
				(width 0.1524)
				(type default)
			)
			(layer "F.SilkS")
		)
		(fp_line
			(start -0.7874 -0.4064)
			(end 0.7874 -0.4064)
			(stroke
				(width 0.1524)
				(type default)
			)
			(layer "F.SilkS")
		)
		(fp_line
			(start 0.67945 0.3048)
			(end 0.120396 0.3048)
			(stroke
				(width 0.1)
				(type default)
			)
			(layer "F.Fab")
		)
		(fp_line
			(start 0.67945 -0.3048)
			(end 0.67945 0.3048)
			(stroke
				(width 0.1)
				(type default)
			)
			(layer "F.Fab")
		)
		(fp_line
			(start 0.12065 -0.2794)
			(end 0.12065 -0.3048)
			(stroke
				(width 0.1)
				(type default)
			)
			(layer "F.Fab")
		)
		(fp_line
			(start 0.12065 -0.3048)
			(end 0.67945 -0.3048)
			(stroke
				(width 0.1)
				(type default)
			)
			(layer "F.Fab")
		)
		(fp_line
			(start 0.120396 0.3048)
			(end 0.120396 0.2794)
			(stroke
				(width 0.1)
				(type default)
			)
			(layer "F.Fab")
		)
		(fp_line
			(start 0.120396 0.2794)
			(end -0.12065 0.2794)
			(stroke
				(width 0.1)
				(type default)
			)
			(layer "F.Fab")
		)
		(fp_line
			(start -0.12065 0.3048)
			(end -0.67945 0.3048)
			(stroke
				(width 0.1)
				(type default)
			)
			(layer "F.Fab")
		)
		(fp_line
			(start -0.12065 0.2794)
			(end -0.12065 0.3048)
			(stroke
				(width 0.1)
				(type default)
			)
			(layer "F.Fab")
		)
		(fp_line
			(start -0.12065 -0.2794)
			(end 0.12065 -0.2794)
			(stroke
				(width 0.1)
				(type default)
			)
			(layer "F.Fab")
		)
		(fp_line
			(start -0.12065 -0.305054)
			(end -0.12065 -0.2794)
			(stroke
				(width 0.1)
				(type default)
			)
			(layer "F.Fab")
		)
		(fp_line
			(start -0.67945 0.3048)
			(end -0.67945 -0.305054)
			(stroke
				(width 0.1)
				(type default)
			)
			(layer "F.Fab")
		)
		(fp_line
			(start -0.67945 -0.305054)
			(end -0.12065 -0.305054)
			(stroke
				(width 0.1)
				(type default)
			)
			(layer "F.Fab")
		)
		(pad "1" smd circle
			(at -0.40005 0 180)
			(size 0 0)
			(layers "F.Cu" "F.Mask" "F.Paste")
			(net "P5V_AUX")
		)
		(pad "2" smd circle
			(at 0.40005 0 180)
			(size 0 0)
			(layers "F.Cu" "F.Mask" "F.Paste")
			(net "P12V_SSD7_PG_G2")
		)
	)
	(footprint ""
		(layer "F.Cu")
		(at 224.022158 -82.643472 180)
		(property "Reference" "R4351"
			(at 0 0 180)
			(layer "F.SilkS")
			(hide yes)
			(effects
				(font
					(size 1.27 1.27)
				)
			)
		)
		(property "Value" ""
			(at 0 0 180)
			(layer "F.Fab")
			(effects
				(font
					(size 1.27 1.27)
				)
			)
		)
		(duplicate_pad_numbers_are_jumpers no)
		(fp_line
			(start 0.7874 0.4064)
			(end -0.7874 0.4064)
			(stroke
				(width 0.1524)
				(type default)
			)
			(layer "F.SilkS")
		)
		(fp_line
			(start 0.7874 -0.4064)
			(end 0.7874 0.4064)
			(stroke
				(width 0.1524)
				(type default)
			)
			(layer "F.SilkS")
		)
		(fp_line
			(start -0.7874 0.4064)
			(end -0.7874 -0.4064)
			(stroke
				(width 0.1524)
				(type default)
			)
			(layer "F.SilkS")
		)
		(fp_line
			(start -0.7874 -0.4064)
			(end 0.7874 -0.4064)
			(stroke
				(width 0.1524)
				(type default)
			)
			(layer "F.SilkS")
		)
		(fp_line
			(start 0.67945 0.3048)
			(end 0.120396 0.3048)
			(stroke
				(width 0.1)
				(type default)
			)
			(layer "F.Fab")
		)
		(fp_line
			(start 0.67945 -0.3048)
			(end 0.67945 0.3048)
			(stroke
				(width 0.1)
				(type default)
			)
			(layer "F.Fab")
		)
		(fp_line
			(start 0.12065 -0.2794)
			(end 0.12065 -0.3048)
			(stroke
				(width 0.1)
				(type default)
			)
			(layer "F.Fab")
		)
		(fp_line
			(start 0.12065 -0.3048)
			(end 0.67945 -0.3048)
			(stroke
				(width 0.1)
				(type default)
			)
			(layer "F.Fab")
		)
		(fp_line
			(start 0.120396 0.3048)
			(end 0.120396 0.2794)
			(stroke
				(width 0.1)
				(type default)
			)
			(layer "F.Fab")
		)
		(fp_line
			(start 0.120396 0.2794)
			(end -0.12065 0.2794)
			(stroke
				(width 0.1)
				(type default)
			)
			(layer "F.Fab")
		)
		(fp_line
			(start -0.12065 0.3048)
			(end -0.67945 0.3048)
			(stroke
				(width 0.1)
				(type default)
			)
			(layer "F.Fab")
		)
		(fp_line
			(start -0.12065 0.2794)
			(end -0.12065 0.3048)
			(stroke
				(width 0.1)
				(type default)
			)
			(layer "F.Fab")
		)
		(fp_line
			(start -0.12065 -0.2794)
			(end 0.12065 -0.2794)
			(stroke
				(width 0.1)
				(type default)
			)
			(layer "F.Fab")
		)
		(fp_line
			(start -0.12065 -0.305054)
			(end -0.12065 -0.2794)
			(stroke
				(width 0.1)
				(type default)
			)
			(layer "F.Fab")
		)
		(fp_line
			(start -0.67945 0.3048)
			(end -0.67945 -0.305054)
			(stroke
				(width 0.1)
				(type default)
			)
			(layer "F.Fab")
		)
		(fp_line
			(start -0.67945 -0.305054)
			(end -0.12065 -0.305054)
			(stroke
				(width 0.1)
				(type default)
			)
			(layer "F.Fab")
		)
		(pad "1" smd circle
			(at -0.40005 0 180)
			(size 0 0)
			(layers "F.Cu" "F.Mask" "F.Paste")
			(net "P3V3_AUX")
		)
		(pad "2" smd circle
			(at 0.40005 0 180)
			(size 0 0)
			(layers "F.Cu" "F.Mask" "F.Paste")
			(net "SSD13_LED_R")
		)
	)
	(footprint ""
		(layer "F.Cu")
		(at 126.63043 -142.035276 180)
		(property "Reference" "PC623"
			(at 0 0 180)
			(layer "F.SilkS")
			(hide yes)
			(effects
				(font
					(size 1.27 1.27)
				)
			)
		)
		(property "Value" ""
			(at 0 0 180)
			(layer "F.Fab")
			(effects
				(font
					(size 1.27 1.27)
				)
			)
		)
		(duplicate_pad_numbers_are_jumpers no)
		(fp_line
			(start 1.524 0.762)
			(end -1.524 0.762)
			(stroke
				(width 0.1524)
				(type default)
			)
			(layer "F.SilkS")
		)
		(fp_line
			(start 1.524 -0.762)
			(end 1.524 0.762)
			(stroke
				(width 0.1524)
				(type default)
			)
			(layer "F.SilkS")
		)
		(fp_line
			(start -1.524 0.762)
			(end -1.524 -0.762)
			(stroke
				(width 0.1524)
				(type default)
			)
			(layer "F.SilkS")
		)
		(fp_line
			(start -1.524 -0.762)
			(end 1.524 -0.762)
			(stroke
				(width 0.1524)
				(type default)
			)
			(layer "F.SilkS")
		)
		(fp_line
			(start 1.1049 0.724916)
			(end 1.1049 -0.724916)
			(stroke
				(width 0.1)
				(type default)
			)
			(layer "F.Fab")
		)
		(fp_line
			(start 1.1049 -0.724916)
			(end -1.1049 -0.724916)
			(stroke
				(width 0.1)
				(type default)
			)
			(layer "F.Fab")
		)
		(fp_line
			(start -1.1049 0.724916)
			(end 1.1049 0.724916)
			(stroke
				(width 0.1)
				(type default)
			)
			(layer "F.Fab")
		)
		(fp_line
			(start -1.1049 -0.724916)
			(end -1.1049 0.724916)
			(stroke
				(width 0.1)
				(type default)
			)
			(layer "F.Fab")
		)
		(pad "1" smd rect
			(at -0.889 0)
			(size 1.016 1.27)
			(layers "F.Cu" "F.Mask" "F.Paste")
			(net "P12V_NIC2_R")
		)
		(pad "2" smd rect
			(at 0.889 0)
			(size 1.016 1.27)
			(layers "F.Cu" "F.Mask" "F.Paste")
			(net "GND")
		)
	)
)
